# TIMECARD (Time Appliance Project (Time Card)) — schematic netlist excerpt (pin names and nets, part order shuffled) for the footprints in the layout excerpt that follows; sources: Cadence DE-HDL packaged netlist, KiCad conversion of R4006-B0001-02_R01.brd

R100  RESISTOR  33OHM 1%  pkg SMC_0402R_H016  page 21 : \1\ = FPGA_OUT_MACUSBPOWER_EN ; \2\ = USB_PWR_EN
R335  RESISTOR  4.7KOHM 1%  pkg SMC_0402R_H016  page 17 : \1\ = XP3R3V_FPGA ; \2\ = UNNAMED_6_LM75BDPTSSOP8_I34_A1

(kicad_pcb
	(version 20260206)
	(generator "pcbnew")
	(generator_version "10.0")
	(general
		(thickness 1.6)
		(legacy_teardrops no)
	)
	(paper "A4")
	(title_block
		(title "timecard-production-celestica-r4006 — R4006-B0001-02_R01.brd")
		(comment 1 "Time Appliance Project (Time Card) / footprints 958-959 of 1113")
	)
	(layers
		(0 "F.Cu" signal "TOP")
		(4 "In1.Cu" signal "L02_GND1")
		(6 "In2.Cu" signal "L03_SIG1")
		(8 "In3.Cu" signal "L04_GND2")
		(10 "In4.Cu" signal "L05_VCC1")
		(12 "In5.Cu" signal "L06_VCC2")
		(14 "In6.Cu" signal "L07_GND3")
		(16 "In7.Cu" signal "L08_SIG2")
		(18 "In8.Cu" signal "L09_GND4")
		(2 "B.Cu" signal "BOTTOM")
		(9 "F.Adhes" user "F.Adhesive")
		(11 "B.Adhes" user "B.Adhesive")
		(13 "F.Paste" user "Package Geometry/Pastemask Top")
		(15 "B.Paste" user "Package Geometry/Pastemask Bottom")
		(5 "F.SilkS" user "Ref Des/Silkscreen Top")
		(7 "B.SilkS" user "Ref Des/Silkscreen Bottom")
		(1 "F.Mask" user "Board Geometry/Soldermask Top")
		(3 "B.Mask" user "Board Geometry/Soldermask Bottom")
		(17 "Dwgs.User" user "User.Drawings")
		(19 "Cmts.User" user "User.Comments")
		(21 "Eco1.User" user "User.Eco1")
		(23 "Eco2.User" user "User.Eco2")
		(25 "Edge.Cuts" user "Board Geometry/Outline")
		(27 "Margin" user)
		(31 "F.CrtYd" user "Package Geometry/Place Bound Top")
		(29 "B.CrtYd" user "Package Geometry/Place Bound Bottom")
		(35 "F.Fab" user "Ref Des/Assembly Top")
		(33 "B.Fab" user "Ref Des/Assembly Bottom")
	)
	(footprint ""
		(layer "B.Cu")
		(at 64.516 -58.039 -90)
		(property "Reference" "R100"
			(at 5.969 -0.34163 270)
			(unlocked yes)
			(layer "B.SilkS")
			(effects
				(font
					(size 0.7874 0.5842)
					(thickness 0.1524)
				)
				(justify mirror)
			)
		)
		(property "Value" "VAL*"
			(at -0.02032 2.13233 270)
			(unlocked yes)
			(layer "B.Fab")
			(hide yes)
			(effects
				(font
					(size 0.7874 0.5842)
					(thickness 0.1524)
				)
				(justify mirror)
			)
		)
		(property "Tolerance" "TOL*"
			(at -0.044704 3.05435 270)
			(unlocked yes)
			(layer "Cmts.User")
			(hide yes)
			(effects
				(font
					(size 0.7874 0.5842)
					(thickness 0.1524)
				)
				(justify mirror)
			)
		)
		(property "User Part Number" "PARTNUM*"
			(at -0.02032 4.024884 270)
			(unlocked yes)
			(layer "Cmts.User")
			(hide yes)
			(effects
				(font
					(size 0.7874 0.5842)
					(thickness 0.1524)
				)
				(justify mirror)
			)
		)
		(property "Device Type" "RESISTOR-G155-133R0-01,33OHM,1%"
			(at -0.008382 1.210564 270)
			(unlocked yes)
			(layer "B.Fab")
			(hide yes)
			(effects
				(font
					(size 0.7874 0.5842)
					(thickness 0.1524)
				)
				(justify mirror)
			)
		)
		(duplicate_pad_numbers_are_jumpers no)
		(fp_line
			(start -1.143 0.5588)
			(end -1.143 -0.5588)
			(stroke
				(width 0.1)
				(type default)
			)
			(layer "B.SilkS")
		)
		(fp_line
			(start 1.143 0.5588)
			(end -1.143 0.5588)
			(stroke
				(width 0.1)
				(type default)
			)
			(layer "B.SilkS")
		)
		(fp_line
			(start -1.143 -0.5588)
			(end 1.143 -0.5588)
			(stroke
				(width 0.1)
				(type default)
			)
			(layer "B.SilkS")
		)
		(fp_line
			(start 1.143 -0.5588)
			(end 1.143 0.5588)
			(stroke
				(width 0.1)
				(type default)
			)
			(layer "B.SilkS")
		)
		(fp_rect
			(start -1.143 -0.5588)
			(end 1.143 0.5588)
			(stroke
				(width 0)
				(type default)
			)
			(fill no)
			(layer "B.CrtYd")
		)
		(fp_line
			(start -0.508 0.3048)
			(end -0.508 -0.3048)
			(stroke
				(width 0.1)
				(type default)
			)
			(layer "B.Fab")
		)
		(fp_line
			(start 0.508 0.3048)
			(end -0.508 0.3048)
			(stroke
				(width 0.1)
				(type default)
			)
			(layer "B.Fab")
		)
		(fp_line
			(start -0.508 -0.3048)
			(end 0.508 -0.3048)
			(stroke
				(width 0.1)
				(type default)
			)
			(layer "B.Fab")
		)
		(fp_line
			(start 0.508 -0.3048)
			(end 0.508 0.3048)
			(stroke
				(width 0.1)
				(type default)
			)
			(layer "B.Fab")
		)
		(pad "1" smd rect
			(at 0.5334 0 90)
			(size 0.7112 0.6096)
			(layers "B.Cu" "B.Mask" "B.Paste")
			(net "FPGA_OUT_MACUSBPOWER_EN")
		)
		(pad "2" smd rect
			(at -0.5334 0 90)
			(size 0.7112 0.6096)
			(layers "B.Cu" "B.Mask" "B.Paste")
			(net "USB_PWR_EN")
		)
		(zone
			(layer "B.Cu")
			(hatch none 0.5)
			(connect_pads
				(clearance 0)
			)
			(min_thickness 0.25)
			(keepout
				(tracks allowed)
				(vias not_allowed)
				(pads allowed)
				(copperpour not_allowed)
				(footprints allowed)
			)
			(placement
				(enabled no)
				(sheetname "")
			)
			(fill
				(thermal_gap 0.5)
				(thermal_bridge_width 0.5)
				(island_removal_mode 0)
			)
			(polygon
				(pts
					(xy 64.8208 -58.1152) (xy 64.2112 -58.1152) (xy 64.2112 -57.9628) (xy 64.8208 -57.9628)
				)
			)
		)
	)
	(footprint ""
		(layer "B.Cu")
		(at 5.588 -74.295 180)
		(property "Reference" "R335"
			(at 2.921 0.34163 0)
			(unlocked yes)
			(layer "B.SilkS")
			(effects
				(font
					(size 0.7874 0.5842)
					(thickness 0.1524)
				)
				(justify mirror)
			)
		)
		(property "Value" "VAL*"
			(at -0.02032 2.13233 180)
			(unlocked yes)
			(layer "B.Fab")
			(hide yes)
			(effects
				(font
					(size 0.7874 0.5842)
					(thickness 0.1524)
				)
				(justify mirror)
			)
		)
		(property "Tolerance" "TOL*"
			(at -0.044704 3.05435 180)
			(unlocked yes)
			(layer "Cmts.User")
			(hide yes)
			(effects
				(font
					(size 0.7874 0.5842)
					(thickness 0.1524)
				)
				(justify mirror)
			)
		)
		(property "User Part Number" "PARTNUM*"
			(at -0.02032 4.024884 180)
			(unlocked yes)
			(layer "Cmts.User")
			(hide yes)
			(effects
				(font
					(size 0.7874 0.5842)
					(thickness 0.1524)
				)
				(justify mirror)
			)
		)
		(property "Device Type" "RESISTOR-G155-14701-01,4.7KOHMA"
			(at -0.008382 1.210564 180)
			(unlocked yes)
			(layer "B.Fab")
			(hide yes)
			(effects
				(font
					(size 0.7874 0.5842)
					(thickness 0.1524)
				)
				(justify mirror)
			)
		)
		(duplicate_pad_numbers_are_jumpers no)
		(fp_line
			(start 1.143 0.5588)
			(end -1.143 0.5588)
			(stroke
				(width 0.1)
				(type default)
			)
			(layer "B.SilkS")
		)
		(fp_line
			(start 1.143 -0.5588)
			(end 1.143 0.5588)
			(stroke
				(width 0.1)
				(type default)
			)
			(layer "B.SilkS")
		)
		(fp_line
			(start -1.143 0.5588)
			(end -1.143 -0.5588)
			(stroke
				(width 0.1)
				(type default)
			)
			(layer "B.SilkS")
		)
		(fp_line
			(start -1.143 -0.5588)
			(end 1.143 -0.5588)
			(stroke
				(width 0.1)
				(type default)
			)
			(layer "B.SilkS")
		)
		(fp_rect
			(start -1.143 0.5588)
			(end 1.143 -0.5588)
			(stroke
				(width 0)
				(type default)
			)
			(fill no)
			(layer "B.CrtYd")
		)
		(fp_line
			(start 0.508 0.3048)
			(end -0.508 0.3048)
			(stroke
				(width 0.1)
				(type default)
			)
			(layer "B.Fab")
		)
		(fp_line
			(start 0.508 -0.3048)
			(end 0.508 0.3048)
			(stroke
				(width 0.1)
				(type default)
			)
			(layer "B.Fab")
		)
		(fp_line
			(start -0.508 0.3048)
			(end -0.508 -0.3048)
			(stroke
				(width 0.1)
				(type default)
			)
			(layer "B.Fab")
		)
		(fp_line
			(start -0.508 -0.3048)
			(end 0.508 -0.3048)
			(stroke
				(width 0.1)
				(type default)
			)
			(layer "B.Fab")
		)
		(pad "1" smd rect
			(at 0.5334 0)
			(size 0.7112 0.6096)
			(layers "B.Cu" "B.Mask" "B.Paste")
			(net "XP3R3V_FPGA")
		)
		(pad "2" smd rect
			(at -0.5334 0)
			(size 0.7112 0.6096)
			(layers "B.Cu" "B.Mask" "B.Paste")
			(net "UNNAMED_6_LM75BDPTSSOP8_I34_A1")
		)
		(zone
			(layer "B.Cu")
			(hatch none 0.5)
			(connect_pads
				(clearance 0)
			)
			(min_thickness 0.25)
			(keepout
				(tracks allowed)
				(vias not_allowed)
				(pads allowed)
				(copperpour not_allowed)
				(footprints allowed)
			)
			(placement
				(enabled no)
				(sheetname "")
			)
			(fill
				(thermal_gap 0.5)
				(thermal_bridge_width 0.5)
				(island_removal_mode 0)
			)
			(polygon
				(pts
					(xy 5.6642 -74.5998) (xy 5.5118 -74.5998) (xy 5.5118 -73.9902) (xy 5.6642 -73.9902)
				)
			)
		)
	)
)
